(kicad_pcb
	(version 20260206)
	(generator "pcbnew")
	(generator_version "10.0")
	(general
		(thickness 1.6)
		(legacy_teardrops no)
	)
	(paper "A4")
	(title_block
		(title "Bryce Canyon_F.DPB_16315-1-OCP.brd")
		(comment 1 "Bryce Canyon / footprint 663 of 2223 (DPB2), pads 1-54 of 54")
	)
	(layers
		(0 "F.Cu" signal "TOP")
		(4 "In1.Cu" signal "L2GND")
		(6 "In2.Cu" signal "L3")
		(8 "In3.Cu" signal "L4GND")
		(10 "In4.Cu" signal "L5")
		(12 "In5.Cu" signal "L6VCC")
		(14 "In6.Cu" signal "L7VCC")
		(16 "In7.Cu" signal "L8")
		(18 "In8.Cu" signal "L9GND")
		(20 "In9.Cu" signal "L10")
		(22 "In10.Cu" signal "L11GND")
		(2 "B.Cu" signal "BOTTOM")
		(9 "F.Adhes" user "F.Adhesive")
		(11 "B.Adhes" user "B.Adhesive")
		(13 "F.Paste" user "Package Geometry/Pastemask Top")
		(15 "B.Paste" user "Package Geometry/Pastemask Bottom")
		(5 "F.SilkS" user "Ref Des/Silkscreen Top")
		(7 "B.SilkS" user "Ref Des/Silkscreen Bottom")
		(1 "F.Mask" user "Board Geometry/Soldermask Top")
		(3 "B.Mask" user "Board Geometry/Soldermask Bottom")
		(17 "Dwgs.User" user "User.Drawings")
		(19 "Cmts.User" user "User.Comments")
		(21 "Eco1.User" user "User.Eco1")
		(23 "Eco2.User" user "User.Eco2")
		(25 "Edge.Cuts" user "Board Geometry/Outline")
		(27 "Margin" user)
		(31 "F.CrtYd" user "Package Geometry/Place Bound Top")
		(29 "B.CrtYd" user "Package Geometry/Place Bound Bottom")
		(35 "F.Fab" user "Ref Des/Assembly Top")
		(33 "B.Fab" user "Ref Des/Assembly Bottom")
	)
	(footprint ""
		(layer "F.Cu")
		(at 264.999978 -418.669978 180)
		(property "Reference" "DPB2"
			(at 0 0 180)
			(layer "F.SilkS")
			(hide yes)
			(effects
				(font
					(size 1.27 1.27)
				)
			)
		)
		(property "Value" "AMP-CONN54-6R-GP"
			(at 31.175452 18.813018 180)
			(unlocked yes)
			(layer "F.Fab")
			(hide yes)
			(effects
				(font
					(size 1.016 1.016)
					(thickness 0.1524)
				)
			)
		)
		(property "Device Type" "PREFIT-54P-216315H542"
			(at 31.175452 17.289018 180)
			(unlocked yes)
			(layer "F.Fab")
			(hide yes)
			(effects
				(font
					(size 1.016 1.016)
					(thickness 0.1524)
				)
			)
		)
		(duplicate_pad_numbers_are_jumpers no)
		(pad "A1" thru_hole circle
			(at 0 0 180)
			(size 1.2192 1.2192)
			(drill 0.739902)
			(layers "*.Cu" "*.Mask")
			(remove_unused_layers no)
			(net "P12V_IN")
			(clearance 0.127)
			(thermal_gap 0.127)
		)
		(pad "A2" thru_hole circle
			(at 3.199892 0 180)
			(size 1.2192 1.2192)
			(drill 0.739902)
			(layers "*.Cu" "*.Mask")
			(remove_unused_layers no)
			(net "P12V_IN")
			(clearance 0.127)
			(thermal_gap 0.127)
		)
		(pad "A3" thru_hole circle
			(at 7.199884 0 180)
			(size 1.2192 1.2192)
			(drill 0.739902)
			(layers "*.Cu" "*.Mask")
			(remove_unused_layers no)
			(net "P12V_IN")
			(clearance 0.127)
			(thermal_gap 0.127)
		)
		(pad "A4" thru_hole circle
			(at 10.40003 0 180)
			(size 1.2192 1.2192)
			(drill 0.739902)
			(layers "*.Cu" "*.Mask")
			(remove_unused_layers no)
			(net "P12V_IN")
			(clearance 0.127)
			(thermal_gap 0.127)
		)
		(pad "A5" thru_hole circle
			(at 14.400022 0 180)
			(size 1.2192 1.2192)
			(drill 0.739902)
			(layers "*.Cu" "*.Mask")
			(remove_unused_layers no)
			(net "P12V_B")
			(clearance 0.127)
			(thermal_gap 0.127)
		)
		(pad "A6" thru_hole circle
			(at 17.599914 0 180)
			(size 1.2192 1.2192)
			(drill 0.739902)
			(layers "*.Cu" "*.Mask")
			(remove_unused_layers no)
			(net "P12V_B")
			(clearance 0.127)
			(thermal_gap 0.127)
		)
		(pad "B1" thru_hole oval
			(at 0 -1.500124 180)
			(size 1.2192 4.2164)
			(drill 0.739902)
			(layers "*.Cu" "*.Mask")
			(remove_unused_layers no)
			(net "P12V_IN")
			(clearance 0.127)
			(thermal_gap 0.127)
			(padstack
				(mode front_inner_back)
				(layer "Inner"
					(shape circle)
					(size 1.2192 1.2192)
					(clearance 0.127)
				)
				(layer "B.Cu"
					(shape circle)
					(size 1.2192 1.2192)
					(clearance 0.127)
				)
			)
		)
		(pad "B2" thru_hole oval
			(at 3.199892 -1.500124 180)
			(size 1.2192 4.2164)
			(drill 0.739902)
			(layers "*.Cu" "*.Mask")
			(remove_unused_layers no)
			(net "P12V_IN")
			(clearance 0.127)
			(thermal_gap 0.127)
			(padstack
				(mode front_inner_back)
				(layer "Inner"
					(shape circle)
					(size 1.2192 1.2192)
					(clearance 0.127)
				)
				(layer "B.Cu"
					(shape circle)
					(size 1.2192 1.2192)
					(clearance 0.127)
				)
			)
		)
		(pad "B3" thru_hole oval
			(at 7.199884 -1.500124 180)
			(size 1.2192 4.2164)
			(drill 0.739902)
			(layers "*.Cu" "*.Mask")
			(remove_unused_layers no)
			(net "P12V_IN")
			(clearance 0.127)
			(thermal_gap 0.127)
			(padstack
				(mode front_inner_back)
				(layer "Inner"
					(shape circle)
					(size 1.2192 1.2192)
					(clearance 0.127)
				)
				(layer "B.Cu"
					(shape circle)
					(size 1.2192 1.2192)
					(clearance 0.127)
				)
			)
		)
		(pad "B4" thru_hole oval
			(at 10.40003 -1.500124 180)
			(size 1.2192 4.2164)
			(drill 0.739902)
			(layers "*.Cu" "*.Mask")
			(remove_unused_layers no)
			(net "P12V_IN")
			(clearance 0.127)
			(thermal_gap 0.127)
			(padstack
				(mode front_inner_back)
				(layer "Inner"
					(shape circle)
					(size 1.2192 1.2192)
					(clearance 0.127)
				)
				(layer "B.Cu"
					(shape circle)
					(size 1.2192 1.2192)
					(clearance 0.127)
				)
			)
		)
		(pad "B5" thru_hole oval
			(at 14.400022 -1.500124 180)
			(size 1.2192 4.2164)
			(drill 0.739902)
			(layers "*.Cu" "*.Mask")
			(remove_unused_layers no)
			(net "P12V_B")
			(clearance 0.127)
			(thermal_gap 0.127)
			(padstack
				(mode front_inner_back)
				(layer "Inner"
					(shape circle)
					(size 1.2192 1.2192)
					(clearance 0.127)
				)
				(layer "B.Cu"
					(shape circle)
					(size 1.2192 1.2192)
					(clearance 0.127)
				)
			)
		)
		(pad "B6" thru_hole oval
			(at 17.599914 -1.500124 180)
			(size 1.2192 4.2164)
			(drill 0.739902)
			(layers "*.Cu" "*.Mask")
			(remove_unused_layers no)
			(net "P12V_B")
			(clearance 0.127)
			(thermal_gap 0.127)
			(padstack
				(mode front_inner_back)
				(layer "Inner"
					(shape circle)
					(size 1.2192 1.2192)
					(clearance 0.127)
				)
				(layer "B.Cu"
					(shape circle)
					(size 1.2192 1.2192)
					(clearance 0.127)
				)
			)
		)
		(pad "C1" thru_hole circle
			(at 0 -2.999994 180)
			(size 1.2192 1.2192)
			(drill 0.739902)
			(layers "*.Cu" "*.Mask")
			(remove_unused_layers no)
			(net "P12V_IN")
			(clearance 0.127)
			(thermal_gap 0.127)
		)
		(pad "C2" thru_hole circle
			(at 3.199892 -2.999994 180)
			(size 1.2192 1.2192)
			(drill 0.739902)
			(layers "*.Cu" "*.Mask")
			(remove_unused_layers no)
			(net "P12V_IN")
			(clearance 0.127)
			(thermal_gap 0.127)
		)
		(pad "C3" thru_hole circle
			(at 7.199884 -2.999994 180)
			(size 1.2192 1.2192)
			(drill 0.739902)
			(layers "*.Cu" "*.Mask")
			(remove_unused_layers no)
			(net "P12V_IN")
			(clearance 0.127)
			(thermal_gap 0.127)
		)
		(pad "C4" thru_hole circle
			(at 10.40003 -2.999994 180)
			(size 1.2192 1.2192)
			(drill 0.739902)
			(layers "*.Cu" "*.Mask")
			(remove_unused_layers no)
			(net "P12V_IN")
			(clearance 0.127)
			(thermal_gap 0.127)
		)
		(pad "C5" thru_hole circle
			(at 14.400022 -2.999994 180)
			(size 1.2192 1.2192)
			(drill 0.739902)
			(layers "*.Cu" "*.Mask")
			(remove_unused_layers no)
			(net "P12V_B")
			(clearance 0.127)
			(thermal_gap 0.127)
		)
		(pad "C6" thru_hole circle
			(at 17.599914 -2.999994 180)
			(size 1.2192 1.2192)
			(drill 0.739902)
			(layers "*.Cu" "*.Mask")
			(remove_unused_layers no)
			(net "P12V_B")
			(clearance 0.127)
			(thermal_gap 0.127)
		)
		(pad "D1" thru_hole circle
			(at 0 -5.750052 180)
			(size 1.2192 1.2192)
			(drill 0.739902)
			(layers "*.Cu" "*.Mask")
			(remove_unused_layers no)
			(net "P12V_IN")
			(clearance 0.127)
			(thermal_gap 0.127)
		)
		(pad "D2" thru_hole circle
			(at 3.199892 -5.750052 180)
			(size 1.2192 1.2192)
			(drill 0.739902)
			(layers "*.Cu" "*.Mask")
			(remove_unused_layers no)
			(net "P12V_IN")
			(clearance 0.127)
			(thermal_gap 0.127)
		)
		(pad "D3" thru_hole circle
			(at 7.199884 -5.750052 180)
			(size 1.2192 1.2192)
			(drill 0.739902)
			(layers "*.Cu" "*.Mask")
			(remove_unused_layers no)
			(net "P12V_IN")
			(clearance 0.127)
			(thermal_gap 0.127)
		)
		(pad "D4" thru_hole circle
			(at 10.40003 -5.750052 180)
			(size 1.2192 1.2192)
			(drill 0.739902)
			(layers "*.Cu" "*.Mask")
			(remove_unused_layers no)
			(net "P12V_IN")
			(clearance 0.127)
			(thermal_gap 0.127)
		)
		(pad "D5" thru_hole circle
			(at 14.400022 -5.750052 180)
			(size 1.2192 1.2192)
			(drill 0.739902)
			(layers "*.Cu" "*.Mask")
			(remove_unused_layers no)
			(net "GND")
			(clearance 0.127)
			(thermal_gap 0.127)
		)
		(pad "D6" thru_hole circle
			(at 17.599914 -5.750052 180)
			(size 1.2192 1.2192)
			(drill 0.739902)
			(layers "*.Cu" "*.Mask")
			(remove_unused_layers no)
			(net "GND")
			(clearance 0.127)
			(thermal_gap 0.127)
		)
		(pad "E1" thru_hole oval
			(at 0 -7.249922 180)
			(size 1.2192 4.2164)
			(drill 0.739902)
			(layers "*.Cu" "*.Mask")
			(remove_unused_layers no)
			(net "P12V_IN")
			(clearance 0.127)
			(thermal_gap 0.127)
			(padstack
				(mode front_inner_back)
				(layer "Inner"
					(shape circle)
					(size 1.2192 1.2192)
					(clearance 0.127)
				)
				(layer "B.Cu"
					(shape circle)
					(size 1.2192 1.2192)
					(clearance 0.127)
				)
			)
		)
		(pad "E2" thru_hole oval
			(at 3.199892 -7.249922 180)
			(size 1.2192 4.2164)
			(drill 0.739902)
			(layers "*.Cu" "*.Mask")
			(remove_unused_layers no)
			(net "P12V_IN")
			(clearance 0.127)
			(thermal_gap 0.127)
			(padstack
				(mode front_inner_back)
				(layer "Inner"
					(shape circle)
					(size 1.2192 1.2192)
					(clearance 0.127)
				)
				(layer "B.Cu"
					(shape circle)
					(size 1.2192 1.2192)
					(clearance 0.127)
				)
			)
		)
		(pad "E3" thru_hole oval
			(at 7.199884 -7.249922 180)
			(size 1.2192 4.2164)
			(drill 0.739902)
			(layers "*.Cu" "*.Mask")
			(remove_unused_layers no)
			(net "P12V_IN")
			(clearance 0.127)
			(thermal_gap 0.127)
			(padstack
				(mode front_inner_back)
				(layer "Inner"
					(shape circle)
					(size 1.2192 1.2192)
					(clearance 0.127)
				)
				(layer "B.Cu"
					(shape circle)
					(size 1.2192 1.2192)
					(clearance 0.127)
				)
			)
		)
		(pad "E4" thru_hole oval
			(at 10.40003 -7.249922 180)
			(size 1.2192 4.2164)
			(drill 0.739902)
			(layers "*.Cu" "*.Mask")
			(remove_unused_layers no)
			(net "P12V_IN")
			(clearance 0.127)
			(thermal_gap 0.127)
			(padstack
				(mode front_inner_back)
				(layer "Inner"
					(shape circle)
					(size 1.2192 1.2192)
					(clearance 0.127)
				)
				(layer "B.Cu"
					(shape circle)
					(size 1.2192 1.2192)
					(clearance 0.127)
				)
			)
		)
		(pad "E5" thru_hole oval
			(at 14.400022 -7.249922 180)
			(size 1.2192 4.2164)
			(drill 0.739902)
			(layers "*.Cu" "*.Mask")
			(remove_unused_layers no)
			(net "GND")
			(clearance 0.127)
			(thermal_gap 0.127)
			(padstack
				(mode front_inner_back)
				(layer "Inner"
					(shape circle)
					(size 1.2192 1.2192)
					(clearance 0.127)
				)
				(layer "B.Cu"
					(shape circle)
					(size 1.2192 1.2192)
					(clearance 0.127)
				)
			)
		)
		(pad "E6" thru_hole oval
			(at 17.599914 -7.249922 180)
			(size 1.2192 4.2164)
			(drill 0.739902)
			(layers "*.Cu" "*.Mask")
			(remove_unused_layers no)
			(net "GND")
			(clearance 0.127)
			(thermal_gap 0.127)
			(padstack
				(mode front_inner_back)
				(layer "Inner"
					(shape circle)
					(size 1.2192 1.2192)
					(clearance 0.127)
				)
				(layer "B.Cu"
					(shape circle)
					(size 1.2192 1.2192)
					(clearance 0.127)
				)
			)
		)
		(pad "F1" thru_hole circle
			(at 0 -8.750046 180)
			(size 1.2192 1.2192)
			(drill 0.739902)
			(layers "*.Cu" "*.Mask")
			(remove_unused_layers no)
			(net "P12V_IN")
			(clearance 0.127)
			(thermal_gap 0.127)
		)
		(pad "F2" thru_hole circle
			(at 3.199892 -8.750046 180)
			(size 1.2192 1.2192)
			(drill 0.739902)
			(layers "*.Cu" "*.Mask")
			(remove_unused_layers no)
			(net "P12V_IN")
			(clearance 0.127)
			(thermal_gap 0.127)
		)
		(pad "F3" thru_hole circle
			(at 7.199884 -8.750046 180)
			(size 1.2192 1.2192)
			(drill 0.739902)
			(layers "*.Cu" "*.Mask")
			(remove_unused_layers no)
			(net "P12V_IN")
			(clearance 0.127)
			(thermal_gap 0.127)
		)
		(pad "F4" thru_hole circle
			(at 10.40003 -8.750046 180)
			(size 1.2192 1.2192)
			(drill 0.739902)
			(layers "*.Cu" "*.Mask")
			(remove_unused_layers no)
			(net "P12V_IN")
			(clearance 0.127)
			(thermal_gap 0.127)
		)
		(pad "F5" thru_hole circle
			(at 14.400022 -8.750046 180)
			(size 1.2192 1.2192)
			(drill 0.739902)
			(layers "*.Cu" "*.Mask")
			(remove_unused_layers no)
			(net "GND")
			(clearance 0.127)
			(thermal_gap 0.127)
		)
		(pad "F6" thru_hole circle
			(at 17.599914 -8.750046 180)
			(size 1.2192 1.2192)
			(drill 0.739902)
			(layers "*.Cu" "*.Mask")
			(remove_unused_layers no)
			(net "GND")
			(clearance 0.127)
			(thermal_gap 0.127)
		)
		(pad "G1" thru_hole circle
			(at 0 -11.500104 180)
			(size 1.2192 1.2192)
			(drill 0.739902)
			(layers "*.Cu" "*.Mask")
			(remove_unused_layers no)
			(net "GND")
			(clearance 0.127)
			(thermal_gap 0.127)
		)
		(pad "G2" thru_hole circle
			(at 3.199892 -11.500104 180)
			(size 1.2192 1.2192)
			(drill 0.739902)
			(layers "*.Cu" "*.Mask")
			(remove_unused_layers no)
			(net "GND")
			(clearance 0.127)
			(thermal_gap 0.127)
		)
		(pad "G3" thru_hole circle
			(at 7.199884 -11.500104 180)
			(size 1.2192 1.2192)
			(drill 0.739902)
			(layers "*.Cu" "*.Mask")
			(remove_unused_layers no)
			(net "GND")
			(clearance 0.127)
			(thermal_gap 0.127)
		)
		(pad "G4" thru_hole circle
			(at 10.40003 -11.500104 180)
			(size 1.2192 1.2192)
			(drill 0.739902)
			(layers "*.Cu" "*.Mask")
			(remove_unused_layers no)
			(net "GND")
			(clearance 0.127)
			(thermal_gap 0.127)
		)
		(pad "G5" thru_hole circle
			(at 14.400022 -11.500104 180)
			(size 1.2192 1.2192)
			(drill 0.739902)
			(layers "*.Cu" "*.Mask")
			(remove_unused_layers no)
			(net "GND")
			(clearance 0.127)
			(thermal_gap 0.127)
		)
		(pad "G6" thru_hole circle
			(at 17.599914 -11.500104 180)
			(size 1.2192 1.2192)
			(drill 0.739902)
			(layers "*.Cu" "*.Mask")
			(remove_unused_layers no)
			(net "GND")
			(clearance 0.127)
			(thermal_gap 0.127)
		)
		(pad "H1" thru_hole oval
			(at 0 -12.999974 180)
			(size 1.2192 4.2164)
			(drill 0.739902)
			(layers "*.Cu" "*.Mask")
			(remove_unused_layers no)
			(net "GND")
			(clearance 0.127)
			(thermal_gap 0.127)
			(padstack
				(mode front_inner_back)
				(layer "Inner"
					(shape circle)
					(size 1.2192 1.2192)
					(clearance 0.127)
				)
				(layer "B.Cu"
					(shape circle)
					(size 1.2192 1.2192)
					(clearance 0.127)
				)
			)
		)
		(pad "H2" thru_hole oval
			(at 3.199892 -12.999974 180)
			(size 1.2192 4.2164)
			(drill 0.739902)
			(layers "*.Cu" "*.Mask")
			(remove_unused_layers no)
			(net "GND")
			(clearance 0.127)
			(thermal_gap 0.127)
			(padstack
				(mode front_inner_back)
				(layer "Inner"
					(shape circle)
					(size 1.2192 1.2192)
					(clearance 0.127)
				)
				(layer "B.Cu"
					(shape circle)
					(size 1.2192 1.2192)
					(clearance 0.127)
				)
			)
		)
		(pad "H3" thru_hole oval
			(at 7.199884 -12.999974 180)
			(size 1.2192 4.2164)
			(drill 0.739902)
			(layers "*.Cu" "*.Mask")
			(remove_unused_layers no)
			(net "GND")
			(clearance 0.127)
			(thermal_gap 0.127)
			(padstack
				(mode front_inner_back)
				(layer "Inner"
					(shape circle)
					(size 1.2192 1.2192)
					(clearance 0.127)
				)
				(layer "B.Cu"
					(shape circle)
					(size 1.2192 1.2192)
					(clearance 0.127)
				)
			)
		)
		(pad "H4" thru_hole oval
			(at 10.40003 -12.999974 180)
			(size 1.2192 4.2164)
			(drill 0.739902)
			(layers "*.Cu" "*.Mask")
			(remove_unused_layers no)
			(net "GND")
			(clearance 0.127)
			(thermal_gap 0.127)
			(padstack
				(mode front_inner_back)
				(layer "Inner"
					(shape circle)
					(size 1.2192 1.2192)
					(clearance 0.127)
				)
				(layer "B.Cu"
					(shape circle)
					(size 1.2192 1.2192)
					(clearance 0.127)
				)
			)
		)
		(pad "H5" thru_hole oval
			(at 14.400022 -12.999974 180)
			(size 1.2192 4.2164)
			(drill 0.739902)
			(layers "*.Cu" "*.Mask")
			(remove_unused_layers no)
			(net "GND")
			(clearance 0.127)
			(thermal_gap 0.127)
			(padstack
				(mode front_inner_back)
				(layer "Inner"
					(shape circle)
					(size 1.2192 1.2192)
					(clearance 0.127)
				)
				(layer "B.Cu"
					(shape circle)
					(size 1.2192 1.2192)
					(clearance 0.127)
				)
			)
		)
		(pad "H6" thru_hole oval
			(at 17.599914 -12.999974 180)
			(size 1.2192 4.2164)
			(drill 0.739902)
			(layers "*.Cu" "*.Mask")
			(remove_unused_layers no)
			(net "GND")
			(clearance 0.127)
			(thermal_gap 0.127)
			(padstack
				(mode front_inner_back)
				(layer "Inner"
					(shape circle)
					(size 1.2192 1.2192)
					(clearance 0.127)
				)
				(layer "B.Cu"
					(shape circle)
					(size 1.2192 1.2192)
					(clearance 0.127)
				)
			)
		)
		(pad "J1" thru_hole circle
			(at 0 -14.500098 180)
			(size 1.2192 1.2192)
			(drill 0.739902)
			(layers "*.Cu" "*.Mask")
			(remove_unused_layers no)
			(net "GND")
			(clearance 0.127)
			(thermal_gap 0.127)
		)
		(pad "J2" thru_hole circle
			(at 3.199892 -14.500098 180)
			(size 1.2192 1.2192)
			(drill 0.739902)
			(layers "*.Cu" "*.Mask")
			(remove_unused_layers no)
			(net "GND")
			(clearance 0.127)
			(thermal_gap 0.127)
		)
		(pad "J3" thru_hole circle
			(at 7.199884 -14.500098 180)
			(size 1.2192 1.2192)
			(drill 0.739902)
			(layers "*.Cu" "*.Mask")
			(remove_unused_layers no)
			(net "GND")
			(clearance 0.127)
			(thermal_gap 0.127)
		)
		(pad "J4" thru_hole circle
			(at 10.40003 -14.500098 180)
			(size 1.2192 1.2192)
			(drill 0.739902)
			(layers "*.Cu" "*.Mask")
			(remove_unused_layers no)
			(net "GND")
			(clearance 0.127)
			(thermal_gap 0.127)
		)
		(pad "J5" thru_hole circle
			(at 14.400022 -14.500098 180)
			(size 1.2192 1.2192)
			(drill 0.739902)
			(layers "*.Cu" "*.Mask")
			(remove_unused_layers no)
			(net "GND")
			(clearance 0.127)
			(thermal_gap 0.127)
		)
		(pad "J6" thru_hole circle
			(at 17.599914 -14.500098 180)
			(size 1.2192 1.2192)
			(drill 0.739902)
			(layers "*.Cu" "*.Mask")
			(remove_unused_layers no)
			(net "GND")
			(clearance 0.127)
			(thermal_gap 0.127)
		)
	)
)
